# BASEBOARD_FAB2 (Tioga Pass) — schematic netlist excerpt (pin names and nets, part order shuffled) for the footprints in the layout excerpt that follows; sources: Cadence DE-HDL packaged netlist, KiCad conversion of Wiwynn_Tioga_Pass_MB.brd

J1G1  SCONN288_H44441004  SCONN  pkg PIP  page 77
  \12v\(1)  = P12V_NVDIMM_GHJ
  VSS(93)  = GND
  DQ(4)  = M_G_DQ<5>
  VSS(92)  = GND
  DQ(0)  = M_G_DQ<1>
  VSS(91)  = GND
  DQS9P  = M_G_DQS_DP<9>
  DQS9N  = M_G_DQS_DN<9>
  VSS(90)  = GND
  DQ(6)  = M_G_DQ<7>
  VSS(89)  = GND
  DQ(2)  = M_G_DQ<3>
  VSS(88)  = GND
  DQ(12)  = M_G_DQ<13>
  VSS(87)  = GND
  DQ(8)  = M_G_DQ<9>
  VSS(86)  = GND
  DQS10P  = M_G_DQS_DP<10>
  DQS10N  = M_G_DQS_DN<10>
  VSS(85)  = GND
  DQ(14)  = M_G_DQ<15>
  VSS(84)  = GND
  DQ(10)  = M_G_DQ<11>
  VSS(83)  = GND
  DQ(20)  = M_G_DQ<21>
  VSS(82)  = GND
  DQ(16)  = M_G_DQ<17>
  VSS(81)  = GND
  DQS11P  = M_G_DQS_DP<11>
  DQS11N  = M_G_DQS_DN<11>
  VSS(80)  = GND
  DQ(22)  = M_G_DQ<23>
  VSS(79)  = GND
  DQ(18)  = M_G_DQ<19>
  VSS(78)  = GND
  DQ(28)  = M_G_DQ<29>
  VSS(77)  = GND
  DQ(24)  = M_G_DQ<25>
  VSS(76)  = GND
  DQS12P  = M_G_DQS_DP<12>
  DQS12N  = M_G_DQS_DN<12>
  VSS(75)  = GND
  DQ(30)  = M_G_DQ<31>
  VSS(74)  = GND
  DQ(26)  = M_G_DQ<27>
  VSS(73)  = GND
  CB(4)  = M_G_ECC<5>
  VSS(72)  = GND
  CB(0)  = M_G_ECC<1>
  VSS(71)  = GND
  DQS17P  = M_G_DQS_DP<17>
  DQS17N  = M_G_DQS_DN<17>
  VSS(70)  = GND
  CB(6)  = M_G_ECC<7>
  VSS(69)  = GND
  CB(2)  = M_G_ECC<3>
  VSS(68)  = GND
  RESET_N  = M_GHJ_RST_N
  VDD(25)  = PVDDQ_GHJ
  CKE(0)  = M_G_CKE<0>
  VDD(24)  = PVDDQ_GHJ
  ACT_N  = M_G_ACT_N
  BG(0)  = M_G_BG<0>
  VDD(23)  = PVDDQ_GHJ
  A12  = M_G_MA<12>
  A9  = M_G_MA<9>
  VDD(22)  = PVDDQ_GHJ
  A8  = M_G_MA<8>
  A6  = M_G_MA<6>
  VDD(21)  = PVDDQ_GHJ
  A3  = M_G_MA<3>
  A1  = M_G_MA<1>
  VDD(20)  = PVDDQ_GHJ
  CK0P  = M_G_CLK_DP<0>
  CK0N  = M_G_CLK_DN<0>
  VDD(19)  = PVDDQ_GHJ
  VTT(1)  = PVTT_GHJ
  EVENT_N  = FM_DIMM_EVENT_COD_N
  A0  = M_G_MA<0>
  VDD(18)  = PVDDQ_GHJ
  BA(0)  = M_G_BA<0>
  A16_RAS_N  = M_G_MA<16>
  VDD(17)  = PVDDQ_GHJ
  S0_N  = M_G_CS_N<0>
  VDD(16)  = PVDDQ_GHJ
  A15_CAS_N  = M_G_MA<15>
  ODT(0)  = M_G_ODT<0>
  VDD(15)  = PVDDQ_GHJ
  S1_N  = M_G_CS_N<1>
  VDD(14)  = PVDDQ_GHJ
  ODT(1)  = M_G_ODT<1>
  VDD(13)  = PVDDQ_GHJ
  S2_N_C(0)  = M_G_CS_N<2>
  VSS(67)  = GND
  DQ(36)  = M_G_DQ<37>
  VSS(66)  = GND
  DQ(32)  = M_G_DQ<33>
  VSS(65)  = GND
  DQS13P  = M_G_DQS_DP<13>
  DQS13N  = M_G_DQS_DN<13>
  VSS(64)  = GND
  DQ(38)  = M_G_DQ<39>
  VSS(63)  = GND
  DQ(34)  = M_G_DQ<35>
  VSS(62)  = GND
  DQ(44)  = M_G_DQ<45>
  VSS(61)  = GND
  DQ(40)  = M_G_DQ<41>
  VSS(60)  = GND
  DQS14P  = M_G_DQS_DP<14>
  DQS14N  = M_G_DQS_DN<14>
  VSS(59)  = GND
  DQ(46)  = M_G_DQ<47>
  VSS(58)  = GND
  DQ(42)  = M_G_DQ<43>
  VSS(57)  = GND
  DQ(52)  = M_G_DQ<53>
  VSS(56)  = GND
  DQ(48)  = M_G_DQ<49>
  VSS(55)  = GND
  DQS15P  = M_G_DQS_DP<15>
  DQS15N  = M_G_DQS_DN<15>
  VSS(54)  = GND
  DQ(54)  = M_G_DQ<55>
  VSS(53)  = GND
  DQ(50)  = M_G_DQ<51>
  VSS(52)  = GND
  DQ(60)  = M_G_DQ<61>
  VSS(51)  = GND
  DQ(56)  = M_G_DQ<57>
  VSS(50)  = GND
  DQS16P  = M_G_DQS_DP<16>
  DQS16N  = M_G_DQS_DN<16>
  VSS(49)  = GND
  DQ(62)  = M_G_DQ<63>
  VSS(48)  = GND
  DQ(58)  = M_G_DQ<59>
  VSS(47)  = GND
  SA(0)  = GND
  SA(1)  = GND
  SCL  = SMB_DDR_GHJ_VPP_SCL
  VPP(4)  = PVPP_GHJ
  VPP(3)  = PVPP_GHJ
  RFU(2)  = TP_CH_G_DIMM_G0_RFU_2
  \12v\(0)  = P12V_NVDIMM_GHJ
  VREFCA  = M_G_VREF
  VSS(46)  = GND
  DQ(5)  = M_G_DQ<4>
  VSS(45)  = GND
  DQ(1)  = M_G_DQ<0>
  VSS(44)  = GND
  DQS0N  = M_G_DQS_DN<0>
  DQS0P  = M_G_DQS_DP<0>
  VSS(43)  = GND
  DQ(7)  = M_G_DQ<6>
  VSS(42)  = GND
  DQ(3)  = M_G_DQ<2>
  VSS(41)  = GND
  DQ(13)  = M_G_DQ<12>
  VSS(40)  = GND
  DQ(9)  = M_G_DQ<8>
  VSS(39)  = GND
  DQS1N  = M_G_DQS_DN<1>
  DQS1P  = M_G_DQS_DP<1>
  VSS(38)  = GND
  DQ(15)  = M_G_DQ<14>
  VSS(37)  = GND
  DQ(11)  = M_G_DQ<10>
  VSS(36)  = GND
  DQ(21)  = M_G_DQ<20>
  VSS(35)  = GND
  DQ(17)  = M_G_DQ<16>
  VSS(34)  = GND
  DQS2N  = M_G_DQS_DN<2>
  DQS2P  = M_G_DQS_DP<2>
  VSS(33)  = GND
  DQ(23)  = M_G_DQ<22>
  VSS(32)  = GND
  DQ(19)  = M_G_DQ<18>
  VSS(31)  = GND
  DQ(29)  = M_G_DQ<28>
  VSS(30)  = GND
  DQ(25)  = M_G_DQ<24>
  VSS(29)  = GND
  DQS3N  = M_G_DQS_DN<3>
  DQS3P  = M_G_DQS_DP<3>
  VSS(28)  = GND
  DQ(31)  = M_G_DQ<30>
  VSS(27)  = GND
  DQ(27)  = M_G_DQ<26>
  VSS(26)  = GND
  CB(5)  = M_G_ECC<4>
  VSS(25)  = GND
  CB(1)  = M_G_ECC<0>
  VSS(24)  = GND
  DQS8N  = M_G_DQS_DN<8>
  DQS8P  = M_G_DQS_DP<8>
  VSS(23)  = GND
  CB(7)  = M_G_ECC<6>
  VSS(22)  = GND
  CB(3)  = M_G_ECC<2>
  VSS(21)  = GND
  CKE(1)  = M_G_CKE<1>
  VDD(12)  = PVDDQ_GHJ
  RFU(0)  = TP_CH_G_DIMM_G0_RFU_0
  VDD(11)  = PVDDQ_GHJ
  BG(1)  = M_G_BG<1>
  ALERT_N  = M_G_ALERT_N
  VDD(10)  = PVDDQ_GHJ
  A11  = M_G_MA<11>
  A7  = M_G_MA<7>
  VDD(9)  = PVDDQ_GHJ
  A5  = M_G_MA<5>
  A4  = M_G_MA<4>
  VDD(8)  = PVDDQ_GHJ
  A2  = M_G_MA<2>
  VDD(7)  = PVDDQ_GHJ
  CK1P  = M_G_CLK_DP<1>
  CK1N  = M_G_CLK_DN<1>
  VDD(6)  = PVDDQ_GHJ
  VTT(0)  = PVTT_GHJ
  PAR  = M_G_PAR
  VDD(5)  = PVDDQ_GHJ
  BA(1)  = M_G_BA<1>
  A10  = M_G_MA<10>
  VDD(4)  = PVDDQ_GHJ
  RFU(1)  = TP_CH_G_DIMM_G0_RFU_1
  A14_WE_N  = M_G_MA<14>
  VDD(3)  = PVDDQ_GHJ
  SAVE_N_NC  = FM_ADR_COMPLETE_GHJ_N
  VDD(2)  = PVDDQ_GHJ
  A13  = M_G_MA<13>
  VDD(1)  = PVDDQ_GHJ
  A17  = M_G_MA<17>
  C(2)  = M_G_C<2>
  VDD(0)  = PVDDQ_GHJ
  S3_N_C(1)  = M_G_CS_N<3>
  SA(2)  = GND
  VSS(20)  = GND
  DQ(37)  = M_G_DQ<36>
  VSS(19)  = GND
  DQ(33)  = M_G_DQ<32>
  VSS(18)  = GND
  DQS4N  = M_G_DQS_DN<4>
  DQS4P  = M_G_DQS_DP<4>
  VSS(17)  = GND
  DQ(39)  = M_G_DQ<38>
  VSS(16)  = GND
  DQ(35)  = M_G_DQ<34>
  VSS(15)  = GND
  DQ(45)  = M_G_DQ<44>
  VSS(14)  = GND
  DQ(41)  = M_G_DQ<40>
  VSS(13)  = GND
  DQS5N  = M_G_DQS_DN<5>
  DQS5P  = M_G_DQS_DP<5>
  VSS(12)  = GND
  DQ(47)  = M_G_DQ<46>
  VSS(11)  = GND
  DQ(43)  = M_G_DQ<42>
  VSS(10)  = GND
  DQ(53)  = M_G_DQ<52>
  VSS(9)  = GND
  DQ(49)  = M_G_DQ<48>
  VSS(8)  = GND
  DQS6N  = M_G_DQS_DN<6>
  DQS6P  = M_G_DQS_DP<6>
  VSS(7)  = GND
  DQ(55)  = M_G_DQ<54>
  VSS(6)  = GND
  DQ(51)  = M_G_DQ<50>
  VSS(5)  = GND
  DQ(61)  = M_G_DQ<60>
  VSS(4)  = GND
  DQ(57)  = M_G_DQ<56>
  VSS(3)  = GND
  DQS7N  = M_G_DQS_DN<7>
  DQS7P  = M_G_DQS_DP<7>
  VSS(2)  = GND
  DQ(63)  = M_G_DQ<62>
  VSS(1)  = GND
  DQ(59)  = M_G_DQ<58>
  VSS(0)  = GND
  VDDSPD  = PVPP_GHJ
  SDA  = SMB_DDR_GHJ_VPP_SDA
  VPP(1)  = PVPP_GHJ
  VPP(0)  = PVPP_GHJ
  VPP(2)  = PVPP_GHJ

(kicad_pcb
	(version 20260206)
	(generator "pcbnew")
	(generator_version "10.0")
	(general
		(thickness 1.6)
		(legacy_teardrops no)
	)
	(paper "A4")
	(title_block
		(title "Wiwynn_Tioga_Pass_MB.brd")
		(comment 1 "Tioga Pass / footprint 2018 of 4770 (J1G1), pads 202-249 of 291")
	)
	(layers
		(0 "F.Cu" signal "TOP")
		(4 "In1.Cu" signal "L2GND")
		(6 "In2.Cu" signal "L3")
		(8 "In3.Cu" signal "L4GND")
		(10 "In4.Cu" signal "L5")
		(12 "In5.Cu" signal "L6GND")
		(14 "In6.Cu" signal "L7VCC")
		(16 "In7.Cu" signal "L8VCC")
		(18 "In8.Cu" signal "L9GND")
		(20 "In9.Cu" signal "L10")
		(22 "In10.Cu" signal "L11GND")
		(24 "In11.Cu" signal "L12")
		(26 "In12.Cu" signal "L13GND")
		(2 "B.Cu" signal "BOTTOM")
		(9 "F.Adhes" user "F.Adhesive")
		(11 "B.Adhes" user "B.Adhesive")
		(13 "F.Paste" user "Package Geometry/Pastemask Top")
		(15 "B.Paste" user "Package Geometry/Pastemask Bottom")
		(5 "F.SilkS" user "Ref Des/Silkscreen Top")
		(7 "B.SilkS" user "Ref Des/Silkscreen Bottom")
		(1 "F.Mask" user "Board Geometry/Soldermask Top")
		(3 "B.Mask" user "Board Geometry/Soldermask Bottom")
		(17 "Dwgs.User" user "User.Drawings")
		(19 "Cmts.User" user "User.Comments")
		(21 "Eco1.User" user "User.Eco1")
		(23 "Eco2.User" user "User.Eco2")
		(25 "Edge.Cuts" user "Board Geometry/Outline")
		(27 "Margin" user)
		(31 "F.CrtYd" user "Package Geometry/Place Bound Top")
		(29 "B.CrtYd" user "Package Geometry/Place Bound Bottom")
		(35 "F.Fab" user "Ref Des/Assembly Top")
		(33 "B.Fab" user "Ref Des/Assembly Bottom")
	)
	(footprint ""
		(layer "F.Cu")
		(at 29.699458 -15.423642 90)
		(property "Reference" "J1G1"
			(at 9.314688 35.070542 0)
			(unlocked yes)
			(layer "F.SilkS")
			(effects
				(font
					(size 0.7874 0.5842)
					(thickness 0.1524)
				)
				(justify left)
			)
		)
		(property "Value" ""
			(at 0 0 90)
			(layer "F.Fab")
			(effects
				(font
					(size 1.27 1.27)
				)
			)
		)
		(duplicate_pad_numbers_are_jumpers no)
		(pad "199" smd rect
			(at 4.59994 45.900086 90)
			(size 1.8034 0.508)
			(layers "F.Cu" "F.Mask" "F.Paste")
			(net "M_G_ECC<6>")
		)
		(pad "200" smd rect
			(at 4.59994 46.74997 90)
			(size 1.8034 0.508)
			(layers "F.Cu" "F.Mask" "F.Paste")
			(net "GND")
		)
		(pad "201" smd rect
			(at 4.59994 47.600108 90)
			(size 1.8034 0.508)
			(layers "F.Cu" "F.Mask" "F.Paste")
			(net "M_G_ECC<2>")
		)
		(pad "202" smd rect
			(at 4.59994 48.449992 90)
			(size 1.8034 0.508)
			(layers "F.Cu" "F.Mask" "F.Paste")
			(net "GND")
		)
		(pad "203" smd rect
			(at 4.59994 49.299876 90)
			(size 1.8034 0.508)
			(layers "F.Cu" "F.Mask" "F.Paste")
			(net "M_G_CKE<1>")
		)
		(pad "204" smd rect
			(at 4.59994 50.150014 90)
			(size 1.8034 0.508)
			(layers "F.Cu" "F.Mask" "F.Paste")
			(net "PVDDQ_GHJ")
		)
		(pad "205" smd rect
			(at 4.59994 50.999898 90)
			(size 1.8034 0.508)
			(layers "F.Cu" "F.Mask" "F.Paste")
			(net "TP_CH_G_DIMM_G0_RFU_0")
		)
		(pad "206" smd rect
			(at 4.59994 51.850036 90)
			(size 1.8034 0.508)
			(layers "F.Cu" "F.Mask" "F.Paste")
			(net "PVDDQ_GHJ")
		)
		(pad "207" smd rect
			(at 4.59994 52.69992 90)
			(size 1.8034 0.508)
			(layers "F.Cu" "F.Mask" "F.Paste")
			(net "M_G_BG<1>")
		)
		(pad "208" smd rect
			(at 4.59994 53.550058 90)
			(size 1.8034 0.508)
			(layers "F.Cu" "F.Mask" "F.Paste")
			(net "M_G_ALERT_N")
		)
		(pad "209" smd rect
			(at 4.59994 54.399942 90)
			(size 1.8034 0.508)
			(layers "F.Cu" "F.Mask" "F.Paste")
			(net "PVDDQ_GHJ")
		)
		(pad "210" smd rect
			(at 4.59994 55.25008 90)
			(size 1.8034 0.508)
			(layers "F.Cu" "F.Mask" "F.Paste")
			(net "M_G_MA<11>")
		)
		(pad "211" smd rect
			(at 4.59994 56.099964 90)
			(size 1.8034 0.508)
			(layers "F.Cu" "F.Mask" "F.Paste")
			(net "M_G_MA<7>")
		)
		(pad "212" smd rect
			(at 4.59994 56.950102 90)
			(size 1.8034 0.508)
			(layers "F.Cu" "F.Mask" "F.Paste")
			(net "PVDDQ_GHJ")
		)
		(pad "213" smd rect
			(at 4.59994 57.799986 90)
			(size 1.8034 0.508)
			(layers "F.Cu" "F.Mask" "F.Paste")
			(net "M_G_MA<5>")
		)
		(pad "214" smd rect
			(at 4.59994 58.650124 90)
			(size 1.8034 0.508)
			(layers "F.Cu" "F.Mask" "F.Paste")
			(net "M_G_MA<4>")
		)
		(pad "215" smd rect
			(at 4.59994 59.500008 90)
			(size 1.8034 0.508)
			(layers "F.Cu" "F.Mask" "F.Paste")
			(net "PVDDQ_GHJ")
		)
		(pad "216" smd rect
			(at 4.59994 60.349892 90)
			(size 1.8034 0.508)
			(layers "F.Cu" "F.Mask" "F.Paste")
			(net "M_G_MA<2>")
		)
		(pad "217" smd rect
			(at 4.59994 61.20003 90)
			(size 1.8034 0.508)
			(layers "F.Cu" "F.Mask" "F.Paste")
			(net "PVDDQ_GHJ")
		)
		(pad "218" smd rect
			(at 4.59994 62.049914 90)
			(size 1.8034 0.508)
			(layers "F.Cu" "F.Mask" "F.Paste")
			(net "M_G_CLK_DP<1>")
		)
		(pad "219" smd rect
			(at 4.59994 62.900052 90)
			(size 1.8034 0.508)
			(layers "F.Cu" "F.Mask" "F.Paste")
			(net "M_G_CLK_DN<1>")
		)
		(pad "220" smd rect
			(at 4.59994 63.749936 90)
			(size 1.8034 0.508)
			(layers "F.Cu" "F.Mask" "F.Paste")
			(net "PVDDQ_GHJ")
		)
		(pad "221" smd rect
			(at 4.59994 64.600074 90)
			(size 1.8034 0.508)
			(layers "F.Cu" "F.Mask" "F.Paste")
			(net "PVTT_GHJ")
		)
		(pad "222" smd rect
			(at 4.59994 70.550024 90)
			(size 1.8034 0.508)
			(layers "F.Cu" "F.Mask" "F.Paste")
			(net "M_G_PAR")
		)
		(pad "223" smd rect
			(at 4.59994 71.399908 90)
			(size 1.8034 0.508)
			(layers "F.Cu" "F.Mask" "F.Paste")
			(net "PVDDQ_GHJ")
		)
		(pad "224" smd rect
			(at 4.59994 72.250046 90)
			(size 1.8034 0.508)
			(layers "F.Cu" "F.Mask" "F.Paste")
			(net "M_G_BA<1>")
		)
		(pad "225" smd rect
			(at 4.59994 73.09993 90)
			(size 1.8034 0.508)
			(layers "F.Cu" "F.Mask" "F.Paste")
			(net "M_G_MA<10>")
		)
		(pad "226" smd rect
			(at 4.59994 73.950068 90)
			(size 1.8034 0.508)
			(layers "F.Cu" "F.Mask" "F.Paste")
			(net "PVDDQ_GHJ")
		)
		(pad "227" smd rect
			(at 4.59994 74.799952 90)
			(size 1.8034 0.508)
			(layers "F.Cu" "F.Mask" "F.Paste")
			(net "TP_CH_G_DIMM_G0_RFU_1")
		)
		(pad "228" smd rect
			(at 4.59994 75.65009 90)
			(size 1.8034 0.508)
			(layers "F.Cu" "F.Mask" "F.Paste")
			(net "M_G_MA<14>")
		)
		(pad "229" smd rect
			(at 4.59994 76.499974 90)
			(size 1.8034 0.508)
			(layers "F.Cu" "F.Mask" "F.Paste")
			(net "PVDDQ_GHJ")
		)
		(pad "230" smd rect
			(at 4.59994 77.350112 90)
			(size 1.8034 0.508)
			(layers "F.Cu" "F.Mask" "F.Paste")
			(net "FM_ADR_COMPLETE_GHJ_N")
		)
		(pad "231" smd rect
			(at 4.59994 78.199996 90)
			(size 1.8034 0.508)
			(layers "F.Cu" "F.Mask" "F.Paste")
			(net "PVDDQ_GHJ")
		)
		(pad "232" smd rect
			(at 4.59994 79.04988 90)
			(size 1.8034 0.508)
			(layers "F.Cu" "F.Mask" "F.Paste")
			(net "M_G_MA<13>")
		)
		(pad "233" smd rect
			(at 4.59994 79.900018 90)
			(size 1.8034 0.508)
			(layers "F.Cu" "F.Mask" "F.Paste")
			(net "PVDDQ_GHJ")
		)
		(pad "234" smd rect
			(at 4.59994 80.749902 90)
			(size 1.8034 0.508)
			(layers "F.Cu" "F.Mask" "F.Paste")
			(net "M_G_MA<17>")
		)
		(pad "235" smd rect
			(at 4.59994 81.60004 90)
			(size 1.8034 0.508)
			(layers "F.Cu" "F.Mask" "F.Paste")
			(net "M_G_C<2>")
		)
		(pad "236" smd rect
			(at 4.59994 82.449924 90)
			(size 1.8034 0.508)
			(layers "F.Cu" "F.Mask" "F.Paste")
			(net "PVDDQ_GHJ")
		)
		(pad "237" smd rect
			(at 4.59994 83.300062 90)
			(size 1.8034 0.508)
			(layers "F.Cu" "F.Mask" "F.Paste")
			(net "M_G_CS_N<3>")
		)
		(pad "238" smd rect
			(at 4.59994 84.149946 90)
			(size 1.8034 0.508)
			(layers "F.Cu" "F.Mask" "F.Paste")
			(net "GND")
		)
		(pad "239" smd rect
			(at 4.59994 85.000084 90)
			(size 1.8034 0.508)
			(layers "F.Cu" "F.Mask" "F.Paste")
			(net "GND")
		)
		(pad "240" smd rect
			(at 4.59994 85.849968 90)
			(size 1.8034 0.508)
			(layers "F.Cu" "F.Mask" "F.Paste")
			(net "M_G_DQ<36>")
		)
		(pad "241" smd rect
			(at 4.59994 86.700106 90)
			(size 1.8034 0.508)
			(layers "F.Cu" "F.Mask" "F.Paste")
			(net "GND")
		)
		(pad "242" smd rect
			(at 4.59994 87.54999 90)
			(size 1.8034 0.508)
			(layers "F.Cu" "F.Mask" "F.Paste")
			(net "M_G_DQ<32>")
		)
		(pad "243" smd rect
			(at 4.59994 88.399874 90)
			(size 1.8034 0.508)
			(layers "F.Cu" "F.Mask" "F.Paste")
			(net "GND")
		)
		(pad "244" smd rect
			(at 4.59994 89.250012 90)
			(size 1.8034 0.508)
			(layers "F.Cu" "F.Mask" "F.Paste")
			(net "M_G_DQS_DN<4>")
		)
		(pad "245" smd rect
			(at 4.59994 90.099896 90)
			(size 1.8034 0.508)
			(layers "F.Cu" "F.Mask" "F.Paste")
			(net "M_G_DQS_DP<4>")
		)
		(pad "246" smd rect
			(at 4.59994 90.950034 90)
			(size 1.8034 0.508)
			(layers "F.Cu" "F.Mask" "F.Paste")
			(net "GND")
		)
	)
)
